1
1
2
2
3
3
4
4
5
5
6
6
D D
C C
B B
A A
timingcard.com
1SHEET OF 7
Cannot open file 
C:\Users\<user>\Desktop\Ti
mecard 
Logo\TIMECARD.jpg.  
File does not exist.
REV DATEP3 09/14/21
1
2
3
GND4 VCC8
7
6
5
U8
NC7WV125K8X
GND
1
2
3
J1
1909763-1
5
1
2
3
4
AN1
901-143-6RFX
GND
R25
49.9R
ANT1_OUT
R14
4.7K
R15
4.7K
+3.3V +3.3V
ANT1_IN
C26
0.1uF
GNDGND
+3.3V
1
2 3
4
D1
8240136
1
2
3
GND4 VCC8
7
6
5
U11
NC7WV125K8X
GND
1
2
3
J3
1909763-1
5
1
2
3
4
AN3
901-143-6RFX
GND
R28
49.9R
ANT3_OUT
R16
4.7K
R17
4.7K
+3.3V +3.3V
ANT3_IN
C27
0.1uF
GNDGND
+3.3V
1
2
3
GND4 VCC8
7
6
5
U16
NC7WV125K8X
GND
1
2
3
J4
1909763-1
5
1
2
3
4
AN4
901-143-6RFX
GND
R34
49.9R
ANT4_OUT
R31
4.7K
R32
4.7K
+3.3V +3.3V
ANT4_IN
C29
0.1uF
GNDGND
+3.3V
1
2
3
GND4 VCC8
7
6
5
U12
NC7WV125K8X
GND
1
2
3
J2
1909763-1
5
1
2
3
4
AN2
901-143-6RFX
GND
R33
49.9R
ANT2_OUT
R29
4.7K
R30
4.7K
+3.3V +3.3V
ANT2_IN
C28
0.1uF
GNDGND
+3.3V
1
2 3
4
D2
8240136
+3.3V
GND
+3.3V
GND
INPUT/OUTPUT SIGNALS
ANT1_IO_OUT
ANT1_IO_IN
ANT2_IO_OUT
ANT2_IO_IN
ANT3_IO_OUT
ANT3_IO_IN
ANT4_IO_OUT
ANT4_IO_IN
PIAN101 
PIAN102 PIAN103 PIAN104 PIAN105 
COAN1 
PIAN201 
PIAN202 PIAN203 PIAN204 PIAN205 
COAN2 
PIAN301 
PIAN302 PIAN303 PIAN304 PIAN305 
COAN3 
PIAN401 
PIAN402 PIAN403 PIAN404 PIAN405 
COAN4 
PIC2601 
PIC2602 COC26 
PIC2701 
PIC2702 COC27 
PIC2801 
PIC2802 
COC28 
PIC2901 
PIC2902 
COC29 
PID101 PID102 
PID103 PID104 COD1 
PID201 PID202 
PID203 PID204 COD2 
PIJ101 
PIJ102 
PIJ103 
COJ1 
PIJ201 
PIJ202 
PIJ203 
COJ2 
PIJ301 
PIJ302 
PIJ303 
COJ3 
PIJ401 
PIJ402 
PIJ403 
COJ4 
PIR1401 
PIR1402 
COR14 
PIR1501 
PIR1502 
COR15 
PIR1601 
PIR1602 
COR16 
PIR1701 
PIR1702 
COR17 
PIR2501 PIR2502 
COR25 
PIR2801 PIR2802 
COR28 
PIR2901 
PIR2902 COR29 
PIR3001 
PIR3002 COR30 
PIR3101 
PIR3102 COR31 
PIR3201 
PIR3202 COR32 
PIR3301 PIR3302 
COR33 
PIR3401 PIR3402 
COR34 
PIU801 
PIU802 
PIU803 
PIU804 
PIU805 
PIU806 
PIU807 
PIU808 
COU8 
PIU1101 
PIU1102 
PIU1103 
PIU1104 
PIU1105 
PIU1106 
PIU1107 
PIU1108 
COU11 
PIU1201 
PIU1202 
PIU1203 
PIU1204 
PIU1205 
PIU1206 
PIU1207 
PIU1208 
COU12 
PIU1601 
PIU1602 
PIU1603 
PIU1604 
PIU1605 
PIU1606 
PIU1607 
PIU1608 
COU16 



1
1
2
2
3
3
4
4
5
5
6
6
D D
C C
B B
A A
timingcard.com
2SHEET OF 7
Cannot open file 
C:\Users\<user>\Desktop\Ti
mecard 
Logo\TIMECARD.jpg.  
File does not exist.
REV DATEP3 09/14/21
+3.3V+3.3V+3.3V+3.3V
LED1 LED2 LED3 LED4
SYSTEM STATUS LEDS
R35
200 OHM
R36
200 OHM
R38
200 OHM
R39
200 OHM
ANODE 1
B2 G3 R4
D13
155124M173200
ANODE 1
B2 G3 R4
D14
155124M173200
ANODE 1
B2 G3 R4
D15
155124M173200
ANODE 1
B2 G3 R4
D16
155124M173200
ANODE 1
B2 G3 R4
D17
155124M173200
ANODE 1
B2 G3 R4
D18
155124M173200
SDB1
AD2
VCC3
GND4
ISET5
SDA6
SCL7 OUT1 8
OUT2 9
OUT3 10
GND11
OUT4 12
OUT5 13
OUT6 14
OUT7 15
OUT8 16
OUT9 17
GND18
OUT10 19
OUT11 20
OUT12 21
OUT13 22
OUT14 23
OUT15 24
GND25 OUT16 26
OUT17 27
OUT18 28EP29
U6
IS32FL3207
+3.3V
IO STATUS LEDS
GNSS 1
GNSS 2
IO 1
IO 2
IO 3
IO 4
C40
0.1uF
C38
1uF
R40
100k
GNDGND GND
C39
0.1uF
GNDGND
+3.3V +3.3V
LED DRIVER (0x6E)
SDA
SCL
R41
4.7K
GND
D3
BLUE
D9
BLUE
D10
BLUE
D11
BLUE
PIC3801 
PIC3802 
COC38 
PIC3901 
PIC3902 
COC39 
PIC4001 
PIC4002 
COC40 
PID301 
PID302 COD3 
PID901 
PID902 COD9 
PID1001 
PID1002 COD10 
PID1101 
PID1102 COD11 
PID1301 
PID1302 
PID1303 
PID1304 
COD13 
PID1401 
PID1402 
PID1403 
PID1404 
COD14 
PID1501 
PID1502 
PID1503 
PID1504 
COD15 
PID1601 
PID1602 
PID1603 
PID1604 
COD16 
PID1701 
PID1702 
PID1703 
PID1704 
COD17 
PID1801 
PID1802 
PID1803 
PID1804 
COD18 
PIR3501 
PIR3502 COR35 
PIR3601 
PIR3602 COR36 
PIR3801 
PIR3802 COR38 
PIR3901 
PIR3902 COR39 
PIR4001 
PIR4002 COR40 
PIR4101 
PIR4102 
COR41 
PIU601 
PIU602 
PIU603 
PIU604 
PIU605 
PIU606 
PIU607 
PIU608 
PIU609 
PIU6010 
PIU6011 
PIU6012 
PIU6013 
PIU6014 
PIU6015 
PIU6016 
PIU6017 
PIU6018 
PIU6019 
PIU6020 
PIU6021 
PIU6022 
PIU6023 
PIU6024 
PIU6025 
PIU6026 
PIU6027 
PIU6028 PIU6029 
COU6 



1
1
2
2
3
3
4
4
5
5
6
6
D D
C C
B B
A A
timingcard.com
*SHEET OF 7
Cannot open file 
C:\Users\<user>\Desktop\Ti
mecard 
Logo\TIMECARD.jpg.  
File does not exist.
REV DATEP3 09/14/21
+5.0V
GND
KEY2
LED4
LED3
LED2
LED1
+5.0V
GND
GPS1_RST
GPS1_TP1
GPS1_TP2
GND
GPS1_RX
MAC_ALARM
MAC_BITE
MAC_FREQ_CTRL
FPGA_MAC_PPS_IN0-
FPGA_MAC_PPS_IN1-
FPGA_MAC_PPS_OUT-
MAC_RF_OUT
SDA
SCL
GND
GPS1_TX
MAC_RX
MAC_TX
MAC_USB+
MAC_USB-
MAC_USB_PWR
GND
PCIE_PERST
KEY1
FPGA_TCK
FPGA_TDO
GND
FPGA_TDI
FPGA_TMS
GND
PCIE_TX3_P
PCIE_TX3_N
PCIE_RX3_P
PCIE_RX3_N
PCIE_TX0_P
PCIE_TX0_N
PCIE_RX0_P
PCIE_RX0_N
GND
PCIE_TX2_P
PCIE_TX2_N
PCIE_RX2_P
PCIE_RX2_N
PCIE_TX1_P
PCIE_TX1_N
PCIE_RX1_P
PCIE_RX1_N
PCIE_CLK_P
PCIE_CLK_N
UART1_TXD
UART1_RXD
IO_LED1
IO_LED2
IO_LED3
IO_LED4
GPS2_RXGPS2_TX
GPS2_TP2
GPS2_TP1
GPS2_RST
ANT1_IO_OUT
ANT1_IO_IN
ANT2_IO_OUT
ANT2_IO_IN
ANT3_IO_OUT
ANT3_IO_IN
ANT4_IO_OUT
ANT4_IO_IN
EXT_GPIO_7
EXT_GPIO_8
EXT_GPIO_9
EXT_GPIO_10
EXT_GPIO_1
EXT_GPIO_2
EXT_GPIO_3
EXT_GPIO_4
ANT1_OUT
ANT1_IN
ANT2_OUT
ANT2_IN
ANT3_OUT
ANT3_IN
ANT4_OUT
ANT4_IN
EXT_EEPROM_WP
AXK680347YG
11 2 2
33 4 4
55 6 6
77 8 8
99 10 10
1111 12 12
1313 14 14
1515 16 16
1717 18 18
1919 20 20
2121 22 22
2323 24 24
2525 26 26
2727 28 28
2929 30 30
3131 32 32
3333 34 34
3535 36 36
3737 38 38
3939 40 40
4141 42 42
4343 44 44
4545 46 46
4747 48 48
4949 50 50
5151 52 52
5353 54 54
5555 56 56
5757 58 58
5959 60 60
6161 62 62
6363 64 64
6565 66 66
6767 68 68
6969 70 70
7171 72 72
7373 74 74
7575 76 76
7777 78 78
7979 80 80
8181 82 82
8383 84 84
J34
Single FPGA Conn
AXK680347YG
11 2 2
33 4 4
55 6 6
77 8 8
99 10 10
1111 12 12
1313 14 14
1515 16 16
1717 18 18
1919 20 20
2121 22 22
2323 24 24
2525 26 26
2727 28 28
2929 30 30
3131 32 32
3333 34 34
3535 36 36
3737 38 38
3939 40 40
4141 42 42
4343 44 44
4545 46 46
4747 48 48
4949 50 50
5151 52 52
5353 54 54
5555 56 56
5757 58 58
5959 60 60
6161 62 62
6363 64 64
6565 66 66
6767 68 68
6969 70 70
7171 72 72
7373 74 74
7575 76 76
7777 78 78
7979 80 80
8181 82 82
8383 84 84
J36
Single FPGA Conn
AXK680347YG
11 2 2
33 4 4
55 6 6
77 8 8
99 10 10
1111 12 12
1313 14 14
1515 16 16
1717 18 18
1919 20 20
2121 22 22
2323 24 24
2525 26 26
2727 28 28
2929 30 30
3131 32 32
3333 34 34
3535 36 36
3737 38 38
3939 40 40
4141 42 42
4343 44 44
4545 46 46
4747 48 48
4949 50 50
5151 52 52
5353 54 54
5555 56 56
5757 58 58
5959 60 60
6161 62 62
6363 64 64
6565 66 66
6767 68 68
6969 70 70
7171 72 72
7373 74 74
7575 76 76
7777 78 78
7979 80 80
8181 82 82
8383 84 84
J35
Single FPGA Conn
AXK680347YG
11 2 2
33 4 4
55 6 6
77 8 8
99 10 10
1111 12 12
1313 14 14
1515 16 16
1717 18 18
1919 20 20
2121 22 22
2323 24 24
2525 26 26
2727 28 28
2929 30 30
3131 32 32
3333 34 34
3535 36 36
3737 38 38
3939 40 40
4141 42 42
4343 44 44
4545 46 46
4747 48 48
4949 50 50
5151 52 52
5353 54 54
5555 56 56
5757 58 58
5959 60 60
6161 62 62
6363 64 64
6565 66 66
6767 68 68
6969 70 70
7171 72 72
7373 74 74
7575 76 76
7777 78 78
7979 80 80
8181 82 82
8383 84 84
J37
Single FPGA Conn
PIJ3401 PIJ3402 
PIJ3403 PIJ3404 
PIJ3405 PIJ3406 
PIJ3407 PIJ3408 
PIJ3409 PIJ34010 
PIJ34011 PIJ34012 
PIJ34013 PIJ34014 
PIJ34015 PIJ34016 
PIJ34017 PIJ34018 
PIJ34019 PIJ34020 
PIJ34021 PIJ34022 
PIJ34023 PIJ34024 
PIJ34025 PIJ34026 
PIJ34027 PIJ34028 
PIJ34029 PIJ34030 
PIJ34031 PIJ34032 
PIJ34033 PIJ34034 
PIJ34035 PIJ34036 
PIJ34037 PIJ34038 
PIJ34039 PIJ34040 
PIJ34041 PIJ34042 
PIJ34043 PIJ34044 
PIJ34045 PIJ34046 
PIJ34047 PIJ34048 
PIJ34049 PIJ34050 
PIJ34051 PIJ34052 
PIJ34053 PIJ34054 
PIJ34055 PIJ34056 
PIJ34057 PIJ34058 
PIJ34059 PIJ34060 
PIJ34061 PIJ34062 
PIJ34063 PIJ34064 
PIJ34065 PIJ34066 
PIJ34067 PIJ34068 
PIJ34069 PIJ34070 
PIJ34071 PIJ34072 
PIJ34073 PIJ34074 
PIJ34075 PIJ34076 
PIJ34077 PIJ34078 
PIJ34079 PIJ34080 
PIJ34081 PIJ34082 
PIJ34083 PIJ34084 
COJ34 
PIJ3501 PIJ3502 
PIJ3503 PIJ3504 
PIJ3505 PIJ3506 
PIJ3507 PIJ3508 
PIJ3509 PIJ35010 
PIJ35011 PIJ35012 
PIJ35013 PIJ35014 
PIJ35015 PIJ35016 
PIJ35017 PIJ35018 
PIJ35019 PIJ35020 
PIJ35021 PIJ35022 
PIJ35023 PIJ35024 
PIJ35025 PIJ35026 
PIJ35027 PIJ35028 
PIJ35029 PIJ35030 
PIJ35031 PIJ35032 
PIJ35033 PIJ35034 
PIJ35035 PIJ35036 
PIJ35037 PIJ35038 
PIJ35039 PIJ35040 
PIJ35041 PIJ35042 
PIJ35043 PIJ35044 
PIJ35045 PIJ35046 
PIJ35047 PIJ35048 
PIJ35049 PIJ35050 
PIJ35051 PIJ35052 
PIJ35053 PIJ35054 
PIJ35055 PIJ35056 
PIJ35057 PIJ35058 
PIJ35059 PIJ35060 
PIJ35061 PIJ35062 
PIJ35063 PIJ35064 
PIJ35065 PIJ35066 
PIJ35067 PIJ35068 
PIJ35069 PIJ35070 
PIJ35071 PIJ35072 
PIJ35073 PIJ35074 
PIJ35075 PIJ35076 
PIJ35077 PIJ35078 
PIJ35079 PIJ35080 
PIJ35081 PIJ35082 
PIJ35083 PIJ35084 
COJ35 
PIJ3601 PIJ3602 
PIJ3603 PIJ3604 
PIJ3605 PIJ3606 
PIJ3607 PIJ3608 
PIJ3609 PIJ36010 
PIJ36011 PIJ36012 
PIJ36013 PIJ36014 
PIJ36015 PIJ36016 
PIJ36017 PIJ36018 
PIJ36019 PIJ36020 
PIJ36021 PIJ36022 
PIJ36023 PIJ36024 
PIJ36025 PIJ36026 
PIJ36027 PIJ36028 
PIJ36029 PIJ36030 
PIJ36031 PIJ36032 
PIJ36033 PIJ36034 
PIJ36035 PIJ36036 
PIJ36037 PIJ36038 
PIJ36039 PIJ36040 
PIJ36041 PIJ36042 
PIJ36043 PIJ36044 
PIJ36045 PIJ36046 
PIJ36047 PIJ36048 
PIJ36049 PIJ36050 
PIJ36051 PIJ36052 
PIJ36053 PIJ36054 
PIJ36055 PIJ36056 
PIJ36057 PIJ36058 
PIJ36059 PIJ36060 
PIJ36061 PIJ36062 
PIJ36063 PIJ36064 
PIJ36065 PIJ36066 
PIJ36067 PIJ36068 
PIJ36069 PIJ36070 
PIJ36071 PIJ36072 
PIJ36073 PIJ36074 
PIJ36075 PIJ36076 
PIJ36077 PIJ36078 
PIJ36079 PIJ36080 
PIJ36081 PIJ36082 
PIJ36083 PIJ36084 
COJ36 
PIJ3701 PIJ3702 
PIJ3703 PIJ3704 
PIJ3705 PIJ3706 
PIJ3707 PIJ3708 
PIJ3709 PIJ37010 
PIJ37011 PIJ37012 
PIJ37013 PIJ37014 
PIJ37015 PIJ37016 
PIJ37017 PIJ37018 
PIJ37019 PIJ37020 
PIJ37021 PIJ37022 
PIJ37023 PIJ37024 
PIJ37025 PIJ37026 
PIJ37027 PIJ37028 
PIJ37029 PIJ37030 
PIJ37031 PIJ37032 
PIJ37033 PIJ37034 
PIJ37035 PIJ37036 
PIJ37037 PIJ37038 
PIJ37039 PIJ37040 
PIJ37041 PIJ37042 
PIJ37043 PIJ37044 
PIJ37045 PIJ37046 
PIJ37047 PIJ37048 
PIJ37049 PIJ37050 
PIJ37051 PIJ37052 
PIJ37053 PIJ37054 
PIJ37055 PIJ37056 
PIJ37057 PIJ37058 
PIJ37059 PIJ37060 
PIJ37061 PIJ37062 
PIJ37063 PIJ37064 
PIJ37065 PIJ37066 
PIJ37067 PIJ37068 
PIJ37069 PIJ37070 
PIJ37071 PIJ37072 
PIJ37073 PIJ37074 
PIJ37075 PIJ37076 
PIJ37077 PIJ37078 
PIJ37079 PIJ37080 
PIJ37081 PIJ37082 
PIJ37083 PIJ37084 
COJ37 



1
1
2
2
3
3
4
4
5
5
6
6
D D
C C
B B
A A
timingcard.com
*SHEET OF 7
Cannot open file 
C:\Users\<user>\Desktop\Ti
mecard 
Logo\TIMECARD.jpg.  
File does not exist.
REV DATEP3 09/14/21
+5.0V
GND
+3.3V
GND GND
GPS1_TP2
GPS1_TP1
GPS1_RX
GPS1_TX
GPS1_RST
GPS
VCC_ANT1
VCC2
TXD3
RST4 RXD 5TP1 6TP2 7GND 8
U9
RCB-F9T VCC4 SCL 1
SDA 3
WP5 GND 2
U7
AT24MAC402-STUM-T
SDA
SCL
+3.3V
GND
C59
0.1uF
C61
0.1uF
C25
0.1uF
+3.3V
GND
EXT_EEPROM_WP
R37
10K
EEPROM
VDD8
VDDIO6
CS 2
SCK 4
SDI 3
SDO 5
GND 1
GND 7
U14
BME280
VDD8
VDDIO5 INT1 4
INT2 9
CS12
SCX13
SDO 1
SDX 14
NC10 NC11 GND 2
GND 3
GND 7
GNDIO 6
U13
BMX160
C33
0.1uF
C32
0.1uF
GNDGND GND
SDA
SCL
+3.3V +3.3V +3.3V
GNDGNDGND
C31
0.1uF
C30
0.1uF
+3.3V+3.3V
SCL
SDA
+3.3V
GND GND
ENVIRONMENT (0x76) IMU (0x68)
SCLSDA
+3.3V+3.3V
R27
4.7K
R26
4.7K
+5.0V
GND
+3.3V
GND GND
GPS2_TP2
GPS2_TP1
GPS2_RX
GPS2_TX
GPS2_RST
VCC_ANT1
VCC2
TXD3
RST4 RXD 5TP1 6TP2 7GND 8
U15
RCB-F9T-1
C36
0.1uF
C37
0.1uF
12
C58
10uF
12
C60
10uF
12
C34
10uF
12
C35
10uF
1
2
3
4
5
6
7
8
9
10
11
12
P3
EXT GPIO
+3.3V
GNDGND
+3.3V
EXT_GPIO_1
EXT_GPIO_2
EXT_GPIO_3
EXT_GPIO_4
EXT_GPIO_7
EXT_GPIO_8
EXT_GPIO_9
EXT_GPIO_10
EXTERNAL GPIO
36-24393-ND
J5
GNSS Standoff
36-24393-ND
J7
GNSS Standoff
36-24393-ND
J8
GNSS Standoff
36-24393-ND
J9
GNSS Standoff
36-24393-ND
J10
GNSS Standoff
36-24393-ND
J11
GNSS Standoff
36-24393-ND
J12
GNSS Standoff
36-24393-ND
J14
GNSS Standoff
335-1156-ND
J15
M3 screw
335-1156-ND
J16
M3 screw
335-1156-ND
J17
M3 screw
335-1156-ND
J18
M3 screw
335-1156-ND
J19
M3 screw
335-1156-ND
J20
M3 screw
335-1156-ND
J21
M3 screw
335-1156-ND
J22
M3 screw
335-1156-ND
J23
M3 screw
335-1156-ND
J24
M3 screw
335-1156-ND
J25
M3 screw
335-1156-ND
J26
M3 screw
335-1156-ND
J27
M3 screw
335-1156-ND
J28
M3 screw
335-1156-ND
J29
M3 screw
335-1156-ND
J30
M3 screw
335-1156-ND
J32
M3 screw
335-1156-ND
J33
M3 screw
PCIe Bracket screws
SQW-104-01-F-D-VS
33
44
5 5
6 6
7 7
8 8
11
22
J6
GNSS Header
SQW-104-01-F-D-VS
33
44
5 5
6 6
7 7
8 8
11
22
J13
GNSS Header
1
2
3
4
P1
AUX Sensor
GND
SDA
SCL
+3.3V
PIC2501 
PIC2502 
COC25 
PIC3001 
PIC3002 
COC30 
PIC3101 
PIC3102 
COC31 
PIC3201 
PIC3202 
COC32 
PIC3301 
PIC3302 
COC33 
PIC3401 
PIC3402 
COC34 PIC3501 
PIC3502 
COC35 
PIC3601 
PIC3602 COC36 
PIC3701 
PIC3702 COC37 
PIC5801 
PIC5802 
COC58 
PIC5901 
PIC5902 
COC59 
PIC6001 
PIC6002 
COC60 
PIC6101 
PIC6102 
COC61 
COJ5 
PIJ601 
PIJ602 
PIJ603 
PIJ604 
PIJ605 
PIJ606 
PIJ607 
PIJ608 
COJ6 
COJ7 
COJ8 
COJ9 
COJ10 
COJ11 
COJ12 
PIJ1301 
PIJ1302 
PIJ1303 
PIJ1304 
PIJ1305 
PIJ1306 
PIJ1307 
PIJ1308 
COJ13 
COJ14 
COJ15 
COJ16 
COJ17 
COJ18 
COJ19 
COJ20 
COJ21 
COJ22 
COJ23 
COJ24 
COJ25 
COJ26 
COJ27 
COJ28 
COJ29 
COJ30 
COJ32 COJ33 
PIP101 
PIP102 
PIP103 
PIP104 
COP1 
PIP301 
PIP302 
PIP303 
PIP304 
PIP305 
PIP306 
PIP307 
PIP308 
PIP309 
PIP3010 
PIP3011 
PIP3012 
COP3 
PIR2601 
PIR2602 COR26 
PIR2701 
PIR2702 COR27 PIR3701 
PIR3702 
COR37 
PIU701 
PIU702 
PIU703 
PIU704 
PIU705 
COU7 
PIU901 
PIU902 
PIU903 
PIU904 PIU905 
PIU906 
PIU907 
PIU908 
COU9 
PIU1301 
PIU1302 
PIU1303 
PIU1304 
PIU1305 
PIU1306 
PIU1307 
PIU1308 
PIU1309 
PIU13010 
PIU13011 
PIU13012 
PIU13013 
PIU13014 
COU13 
PIU1401 
PIU1402 
PIU1403 
PIU1404 
PIU1405 
PIU1406 
PIU1407 
PIU1408 
COU14 
PIU1501 
PIU1502 
PIU1503 
PIU1504 PIU1505 
PIU1506 
PIU1507 
PIU1508 
COU15 



1
1
2
2
3
3
4
4
5
5
6
6
D D
C C
B B
A A
timingcard.com
*SHEET OF 7
Cannot open file 
C:\Users\<user>\Desktop\Ti
mecard 
Logo\TIMECARD.jpg.  
File does not exist.
REV DATEP3 09/14/21
MAC_TX
MAC_RX
MAC_BITEMAC_RF_OUT
MAC_FREQ_CTRL
FPGA_MAC_PPS_IN0-
MAC_USB+
MAC_USB-
MAC_USB_PWR
MAC_PPS_OUT+
MAC_PPS_OUT-
MAC_ALARM
GND
GND
GND
MAC
10uF
C62
FREQ CTRL INP1
GND (CASE)P2
RF OUTP3
GND (SUPPLY & SIGNAL)P4 VCC P5BITE P6RS-232 TX P7RS-232 RX P8
RV-3049-C3
PPS-IN P9
PPS-OUT P10
U10A
RV-3049-C3
PPS-IN 1+1 USB DATA + 2
PPS-IN 1-3 USB DATA - 4
PPS-IN 0+5 USB POWER 6
PPS-IN 0-7
GND 8
GND 9
NC10
NC11
NC12
NC13
NC14
GND 15NC16
PPS-OUT + 17
NC18
PPS-OUT - 19
ALARM 20
U10B
C63
0.1uF
DI12
DI23
DO+1 7
DO+2 6
DO-1 8
DO-2 5
GND 4VCC1
U3
DS90LV027AQMA
RIN1-1 RIN1+2
RIN2+3
RIN2-4
GND 5
ROUT2 6
ROUT1 7
VCC8
U4
DS90LV028AQMA
R11
4.7K
R10
4.7K C23
0.1uF
GNDGNDGND
+3.3V
MAC_PPS_IN1-
MAC_PPS_IN1+
MAC_PPS_IN0-
MAC_PPS_IN0+
GND
MAC_PPS_IN1-
MAC_PPS_IN1+
MAC_PPS_IN0-
MAC_PPS_IN0+
R12
110R
C24
0.1uF
+3.3V
GND GND
R13
49.9R
FPGA_MAC_PPS_OUT-
MAC_PPS_OUT+
MAC_PPS_OUT-
FPGA_MAC_PPS_IN1-
R43
DNI_49.9R
MAC_PPS_IN
MAC_PPS_OUT
MAC_PPS_OUT
R42
DNI_49.9R
MAC_PPS_IN
11
33
55
77
1010
1111
1212
1313
1414
1616
1818
WM24007CT-ND
2 2
4 4
6 6
17 17
19 19
20 20
8 8
9 9
15 15
J31
SA53_Header
GND
R45
0_5%_1206
R46
DNI_0_5%_1206
+5.0V +12V
12V and 3.3V Option for different Atomic clocks
MAC_VCC
R47
DNI_0_5%_1206
+3.3V
PIC2301 
PIC2302 COC23 
PIC2401 
PIC2402 
COC24 
PIC6201 
PIC6202 
COC62 
PIC6301 
PIC6302 COC63 
PIJ3101 PIJ3102 
PIJ3103 PIJ3104 
PIJ3105 PIJ3106 
PIJ3107 
PIJ3108 
PIJ3109 
PIJ31010 
PIJ31011 
PIJ31012 
PIJ31013 
PIJ31014 
PIJ31015 
PIJ31016 
PIJ31017 
PIJ31018 
PIJ31019 
PIJ31020 
COJ31 
PIR1001 
PIR1002 
COR10 
PIR1101 
PIR1102 
COR11 
PIR1201 
PIR1202 
COR12 
PIR1301 PIR1302 
COR13 
PIR4201 PIR4202 
COR42 
PIR4301 PIR4302 
COR43 
PIR4501 PIR4502 
COR45 
PIR4601 PIR4602 
COR46 
PIR4701 PIR4702 
COR47 
PIU301 
PIU302 
PIU303 
PIU304 
PIU305 
PIU306 
PIU307 
PIU308 
COU3 
PIU401 
PIU402 
PIU403 
PIU404 
PIU405 
PIU406 
PIU407 
PIU408 
COU4 
PIU100P1 
PIU100P2 
PIU100P3 
PIU100P4 PIU100P5 
PIU100P6 
PIU100P7 
PIU100P8 
PIU100P9 
PIU100P10 
COU10A 
PIU1001 PIU1002 
PIU1003 PIU1004 
PIU1005 PIU1006 
PIU1007 
PIU1008 
PIU1009 
PIU10010 
PIU10011 
PIU10012 
PIU10013 
PIU10014 
PIU10015 
PIU10016 
PIU10017 
PIU10018 
PIU10019 
PIU10020 
COU10B 



1
1
2
2
3
3
4
4
5
5
6
6
D D
C C
B B
A A
timingcard.com
*SHEET OF 7
Cannot open file 
C:\Users\<user>\Desktop\Ti
mecard 
Logo\TIMECARD.jpg.  
File does not exist.
REV DATEP3 09/14/21
GND GND
+12V_PCIE+3.3V_PCIE
+3.3V
+3.3V_PCIE
+12V_PCIE
PCIE_RX0_P
PCIE_RX0_N
PCIE_RX1_P
PCIE_RX1_N
PCIE_RX2_P
PCIE_RX2_N
PCIE_RX3_P
PCIE_RX3_N
PCIE_PERST
PCIE_CLK_P
PCIE_CLK_N
PCIE_TX0_P
PCIE_TX0_N
PCIE_TX1_P
PCIE_TX1_N
PCIE_TX2_P
PCIE_TX2_N
PCIE_TX3_P
PCIE_TX3_N
PCIe Connector
4.7K
R22
0.1UFC53
0.1UFC52
0 OHM
R24
0 OHM
R23
0.1UFC51
0.1UFC49
0.1UFC47
0.1UFC45
0.1UFC44
0.1UFC46
0.1UFC48
0.1UFC50
KEY KEY
+12v1B1
+12V2B2
+12V3B3
GND1B4
SMCLKB5
SMDATAB6
GND2B7
+3.3V1B8
JTAG/TRST_nB9
+3.3vauxB10
WAKE_nB11
RESERVED1B12
GND3B13
PETp0B14
PETn0B15
GND4B16
PRSNT2_nB17
GND5B18
PETp1B19
PETn1B20
GND6B21
GND7B22
PETp2B23
PETn2B24
GND8B25
GND9B26
PETp3B27
PETn3B28
GND10B29
RESERVED2B30
PRSNT4_nB31
GND11B32
PRSNT1_n A1
+12V5 A2
+12V4 A3
GND37 A4
JTAG/TCK A5
JTAG/TDI A6
JTAG/TDO A7
JTAG/TMS A8
+3.3V3 A9
+3.3V2 A10
PERST A11
GND36 A12
REFCLK+ A13
REFCLK- A14
GND35 A15
PERp0 A16
PERn0 A17
GND34 A18
RESERVED5 A19
GND33 A20
PERp1 A21
PERn1 A22
GND32 A23
GND31 A24
PERp2 A25
PERn2 A26
GND30 A27
GND29 A28
PERp3 A29
PERn3 A30
GND28 A31
RESERVED4 A32
P2
PCIex4
GND
+3.3V
GND GND GND GND+3.3V +3.3V +3.3V +3.3V
FPGA_TCK
FPGA_TDO
FPGA_TMS
FPGA_TDI
JTAG
33 OHM
R18
33 OHM
R19
33 OHM
R20
33 OHM
R21
2X5
9
3
10
4
1
5
7
2
6
8
U5
BAT54SW
2
3
1
D8
BAT54SW
2
3
1
D7
BAT54SW
2
3
1
D6
BAT54SW
2
3
1
D5
PRSNT
PRSNT
PRSNT
FPGA_TCK FPGA_TDO FPGA_TMS FPGA_TDI
PIC4401 PIC4402 
COC44 
PIC4501 PIC4502 
COC45 
PIC4601 PIC4602 
COC46 
PIC4701 PIC4702 
COC47 
PIC4801 PIC4802 
COC48 
PIC4901 PIC4902 
COC49 
PIC5001 PIC5002 
COC50 
PIC5101 PIC5102 
COC51 
PIC5201 PIC5202 
COC52 
PIC5301 PIC5302 
COC53 
PID501 PID502 
PID503 
COD5 
PID601 PID602 
PID603 
COD6 
PID701 PID702 
PID703 
COD7 
PID801 PID802 
PID803 
COD8 
PIP20A1 
PIP20A2 
PIP20A3 
PIP20A4 
PIP20A5 
PIP20A6 
PIP20A7 
PIP20A8 
PIP20A9 
PIP20A10 
PIP20A11 
PIP20A12 
PIP20A13 
PIP20A14 
PIP20A15 
PIP20A16 
PIP20A17 
PIP20A18 
PIP20A19 
PIP20A20 
PIP20A21 
PIP20A22 
PIP20A23 
PIP20A24 
PIP20A25 
PIP20A26 
PIP20A27 
PIP20A28 
PIP20A29 
PIP20A30 
PIP20A31 
PIP20A32 
PIP20B1 
PIP20B2 
PIP20B3 
PIP20B4 
PIP20B5 
PIP20B6 
PIP20B7 
PIP20B8 
PIP20B9 
PIP20B10 
PIP20B11 
PIP20B12 
PIP20B13 
PIP20B14 
PIP20B15 
PIP20B16 
PIP20B17 
PIP20B18 
PIP20B19 
PIP20B20 
PIP20B21 
PIP20B22 
PIP20B23 
PIP20B24 
PIP20B25 
PIP20B26 
PIP20B27 
PIP20B28 
PIP20B29 
PIP20B30 
PIP20B31 
PIP20B32 
COP2 
PIR1801 PIR1802 
COR18 
PIR1901 PIR1902 
COR19 
PIR2001 PIR2002 
COR20 
PIR2101 PIR2102 
COR21 
PIR2201 
PIR2202 
COR22 
PIR2301 PIR2302 
COR23 
PIR2401 PIR2402 
COR24 
PIU501 PIU502 
PIU503 PIU504 
PIU505 PIU506 
PIU507 PIU508 
PIU509 PIU5010 
COU5 



1
1
2
2
3
3
4
4
5
5
6
6
D D
C C
B B
A A
timingcard.com
*SHEET OF 7
Cannot open file 
C:\Users\<user>\Desktop\Ti
mecard 
Logo\TIMECARD.jpg.  
File does not exist.
REV DATEP3 09/14/21
+12V
GND
+5.0V
+3.3V
GND GND
GNDGND GND
+3.3V
+12V
+12V
10uF
C1
10uF
C6
10uF
C14
10uF
C13
10uF
C5
10uF
C7
10uF
C8
RED
D4
200 OHM
R1
47K
R2
2.2K
R8
10K
R6
47K
R4
0.01uF
C4
10.uH
L1
10.uH
L2
0.01uF
C3
47K
R3
10K
R7
2.2K
R9
26.1K
R5
MP1482DS
BS 1
IN 2
SW 3
FB 5
EN7
SS8
GND4
COMP6
U1
MP1482DS
BS 1
IN 2
SW 3
FB 5
EN7
SS8
GND4
COMP6
U2
2.00A
F1
C2
0.1uF
C15
0.1uF
C16
0.1uF
C17
0.1uF
C18
0.1uFC19
0.1uF
C21
0.1uF
C9
0.1uF
C10
0.1uF
C11
0.1uF
C12
0.1uF
C22
0.033uF
C20
0.033uF
GND
2X3
6
5
4
3
2
1J38
+12V_PCIE
2 1
D12
STPS5L60S
2 1
D19
STPS5L60S
R44
DNI_0_5%_1206
PIC101 
PIC102 
COC1 
PIC201 
PIC202 COC2 
PIC301 PIC302 
COC3 
PIC401 PIC402 
COC4 
PIC501 
PIC502 
COC5 
PIC601 
PIC602 
COC6 
PIC701 
PIC702 
COC7 PIC801 
PIC802 
COC8 
PIC901 
PIC902 
COC9 
PIC1001 
PIC1002 
COC10 
PIC1101 
PIC1102 
COC11 
PIC1201 
PIC1202 
COC12 
PIC1301 
PIC1302 
COC13 PIC1401 
PIC1402 
COC14 
PIC1501 
PIC1502 
COC15 
PIC1601 
PIC1602 
COC16 
PIC1701 
PIC1702 
COC17 
PIC1801 
PIC1802 
COC18 
PIC1901 
PIC1902 COC19 
PIC2001 
PIC2002 
COC20 
PIC2101 
PIC2102 
COC21 
PIC2201 
PIC2202 
COC22 
PID401 
PID402 
COD4 
PID1201 PID1202 
COD12 
PID1901 PID1902 
COD19 
PIF101 PIF102 
COF1 
PIJ3801 
PIJ3802 
PIJ3803 
PIJ3804 
PIJ3805 
PIJ3806 
COJ38 
PIL101 PIL102 
COL1 
PIL201 PIL202 
COL2 
PIR101 
PIR102 
COR1 
PIR201 
PIR202 
COR2 
PIR301 
PIR302 
COR3 
PIR401 PIR402 
COR4 
PIR501 PIR502 
COR5 
PIR601 
PIR602 
COR6 
PIR701 
PIR702 
COR7 
PIR801 PIR802 
COR8 
PIR901 PIR902 
COR9 
PIR4401 PIR4402 
COR44 
PIU101 PIU102 
PIU103 
PIU104 
PIU105 
PIU106 
PIU107 
PIU108 
COU1 
PIU201 PIU202 
PIU203 
PIU204 
PIU205 
PIU206 
PIU207 
PIU208 
COU2 



Line # DNP Name Description Designator Revision ID Revision State Revision Status Quantity Manufacturer 1 Manufacturer Part Number 1 Manufacturer Lifecycle 1 Supplier 1 Supplier Part Number 1 Supplier Unit Price 1 Supplier Subtotal 1
39-30-1060 CONN, HDR, 2X3, R/A, 4.2MM, TH, MINI-FIT JR J38 Not managed 1 Digi-Key WM14977-ND
155124M173200 LED (Multiple) D13, D14, D15, D16, D17, D18 Not managed 6 Wurth Electronics 155124M173200
AUX Sensor Header, 4-Pin P1 Not managed 1
BAT54SW DIO, SCHOTTKY, BAT54S, DUAL SERIES, 30V, 200MA, SC-70 D5, D6, D7, D8 Not managed 4 Diodes BAT54SWQ-7-F Volume Production Digi-Key BAT54SWQ-7-FDICT-ND
CAP_0402_0.1UF_50V CAP, CER, 0.1UF, 50V, 10%, X7R, AEC-Q200, 0402 C44, C45, C46, C47, C48, C49, C50, C51, C52, C53 Not managed 10 TDK CGA2B3X7R1H104K050BB Volume Production Digi-Key 445-6899-1-ND
CAP_0603_0.01UF_50V CAP, CER, 0.01UF, 50V, 10%, X7R, 0603 C3, C4 Not managed 2 KEMET C0603C103K5RACTU Volume Production Digi-Key 399-1091-1-ND
CAP_0805_10UF_25V CAP, CER, 10.UF, 25V, 10%, X5R, 0805 C1, C5, C6, C7, C8, C13, C14, C62 Not managed 8 Taiyo Yuden TMK212BBJ106KG-T Volume Production MOUSER 963-TMK212BBJ106KG-T
CRCW080533R0FKEA RES, 33 OHM, 1%, 1/8W, TF, 0805 R18, R19, R20, R21 Not managed 4 Vishay CRCW080533R0FKEA Volume Production Digi-Key 541-33.0CCT-ND
ERJ-2GE0R00X RES, 0. OHM, 1%, 1/16W, TF, AEC-Q200, 0402 R23, R24 Not managed 2 Panasonic ERJ-2GE0R00X Volume Production Digi-Key P0.0JCT-ND
ERJ-3EKF1002V RES, 10K, 1%, 1/10W, TF, 0603 R6, R7 Not managed 2 Panasonic ERJ-3EKF1002V Volume Production Digi-Key P10.0KHCT-ND
ERJ-3EKF2000V RES, 200 OHM, 1%, 1/10W, TF, 0603 R1 Not managed 1 Panasonic ERJ-3EKF2000V Volume Production Digi-Key P200HCT-ND
ERJ-3EKF2201V RES, 2.2K, 1%, 1/10W, TF, 0603 R8, R9 Not managed 2 Panasonic ERJ-3EKF2201V Volume Production Digi-Key P2.20KHCT-ND
ERJ-3EKF2612V RES, 26.1K, 1%, 1/10W, TF, 0603 R5 Not managed 1 Panasonic ERJ-3EKF2612V Volume Production Digi-Key P26.1KHCT-ND
ERJ-3EKF4701V RES, 4.7K, 1%, 1/10W, TF, 0603 R22 Not managed 1 Panasonic ERJ-3EKF4701V Volume Production Digi-Key P4.70KHCT-ND
ERJ-3EKF4702V RES, 47K, 1%, 1/10W, TF, 0603 R2, R3, R4 Not managed 3 Panasonic ERJ-3EKF4702V Digi-Key P47.0KHCT-ND
FUSE_0603_2.00A FUSE SLOW 2.00A 32V M 0603 F1 Not managed 1 Bourns SF-0603S200-2 Volume Production Digi-Key SF-0603S200-2CT-ND
GNSS Header 8-pin GNSS header J6, J13 Not managed 2 Digi-Key SAM11876-ND
GNSS Standoff J5, J7, J8, J9, J10, J11, J12, J14 Not managed 8Keystone 
Electronics 24393 Volume Production Digi-Key 36-24393-ND
IS32FL3207 U6 Not managed 1 ISSI IS32FL3207-QWLA3-TR
M3 screw J15, J16, J17, J18, J19, J20, J21, J22, J23, J24, J25, J26, J27, J28, J29, J30, 
J32, J33 Not managed 18 APM Hexseal RM3X10MM2701 Volume Production Digi-Key 335-1156-ND
MP1482DS-LF IC, DC/DC, MP1482DS, >4.75VIN, 0.923-15V OUT, SOIC8 U1, U2 Not managed 2Monolithic Power 
Systems MP1482DS-LF-Z Digi-Key 1589-1524-1-ND
NC7WV125K8X Integrated Circuit U8, U11, U12, U16 Not managed 4
ON 
Semiconductor / 
Fairchild
NC7WV125K8X Volume Production
PM124SH-100M-RC IND, PWR, 10.uH, 20%, 4A, 0.04DCR, 12.5X12.5MM, SHLD L1, L2 Not managed 2 Bourns JW Miller PM124SH-100M-RC Volume Production Digi-Key PM124SH-100M-RCCT-ND
RED LED, RED, SML-LX0603, 635NM, 2V, 20MA, 0603 D4 Not managed 1 Vishay TLMS1100-GS08 Volume Production Digi-Key 67-1548-1-ND
SA53_Header J31 Not managed 1 Molex 52991-0208 Volume Production Digi-Key WM24007CT-ND
Single FPGA Conn J34, J35, J36, J37 Not managed 4 Digi-Key 255-3246-1-ND
DNP EXT GPIO Header, 6-Pin, Dual row P3 Not managed 1
DNP HTST-105-01-L-DV-A CONN, HDR, 2X5, VERT, 0.1IN  SHROUDED, SMT, HTSH SERIES U5 Not managed 1 Samtec HTST-105-01-L-DV-A Volume Production Digi-Key SAM8809-ND
DNP MAC-SA5X MOD, MAC, MAC-SA5X, ATOMIC CLOCK U10 Not managed 1
DNP PCIex4 PCIE x4 Edge Connector,OrCAD Symbol,NC P2 Not managed 1
DNP RCB-F9T MOD, GPS U9 Not managed 1 u-blox RCB-F9T Digi-Key 672-RCB-F9T-ND
DNP RCB-F9T-1 MOD, GPS U15 Not managed 1 u-blox RCB-F9T Digi-Key 672-RCB-F9T-ND
0_5%_1206 R45 Unknown server 1
0.033uF GCM188R71H333KA55D C20, C22 Unknown server 2 Murata GCM188R71H333KA55D
0.1uF C0603X104K5RACAUTO C2, C9, C10, C11, C12, C15, C16, C17, C18, C19, C21, C23, C24, C25, C26, 
C27, C28, C29, C30, C31, C32, C33, C36, C37, C39, C40, C59, C61, C63 Unknown server 29 KEMET C0603X104K5RACAUTO Volume Production
1uF CAP CER 1UF 25V X5R 0603 C38 Unknown server 1 KEMET C0603C105K3PACTU Volume Production
4.7K Chip Resistor, 4.7 KOhm, +/- 1%, 0.1 W, -55 to 155 degC, 0603 (1608 
Metric), RoHS, Tape and Reel RC0603FR-074K7L R10, R11 Unknown server 2 Yageo RC0603FR-074K7L Volume Production
4.7K Precision Thick Film Chip Resistor, 4.7 KOhm, +/- 1%, -55 to 155 
degC, 0603 (1608 Metric), RoHS, Tape and Reel ERJ-3EKF4701V R14, R15, R16, R17, R26, R27, R29, R30, R31, R32, R41 Unknown server 11 Vishay Dale CRCW06034K70FKTB
10K Chip Resistor, 10 KOhm, +/- 1%, 0.1 W, -55 to 155 degC, 0603 (1608 
Metric), RoHS, Tape and Reel RMCF0603FT10K0 R37 Unknown server 1Stackpole 
Electronics RMCF0603FT10K0 Volume Production
10uF None C34, C35, C58, C60 Unknown server 4 Taiyo Yuden TMK212BBJ106KG-T Volume Production
49.9R General Purpose Chip Resistor, 49.9 Ohm, +/- 1%, -55 to 155 degC, 
0603 (1608 Metric), RoHS, Tape and Reel R13, R25, R28, R33, R34 Unknown server 5 Yageo RC0603FR-0749R9L Volume Production
100k RES SMD 100K OHM 1% 1/10W 0603 R40 Unknown server 1 Yageo RC0603FR-07100KL Volume Production
110R R12 Unknown server 1 Vishay CRCW0603110RFKEA Volume Production
200 OHM ERJ-3EKF2000V R35, R36, R38, R39 Unknown server 4 Panasonic ERJ-3EKF2000V Volume Production
901-143-6RFX Coaxial connector, 50 Ohm, -65 to 165 degC, 5-Pin THD, RoHS, Bulk AN1, AN2, AN3, AN4 Unknown server 4 Amphenol RF 901-143-6RFX Volume Production
1909763-1 Ultra Miniature Coaxial Connector Jack, 60 V, 50 Ohm, -40 to 90 
degC, RoHS, Tape and Reel J1, J2, J3, J4 Unknown server 4TE Connectivity 
AMP 1909763-1 Volume Production
8240136 TVS Diode WE-TVS-HS, VRWM=3.3V D1, D2 Unknown server 2 Wurth Electronics 8240136 Volume Production
AT24MAC402-STUM-T IC EEPROM 2K I2C 1MHZ SOT23-5 U7 Unknown server 1 Microchip AT24MAC402-STUM-T
BLUE LED BLUE CLEAR CHIP SMD D3, D9, D10, D11 Unknown server 4 Vishay Lite-On LTST-C191TBKT Volume Production
DS90LV027AQMA Automotive LVDS Dual Differential Driver, 8-pin Narrow SOIC U3 Unknown server 1
DS90LV028AQMA Automotive LVDS Dual Differential Line Receiver, 8-pin Narrow SOIC U4 Unknown server 1
STPS5L60S DIODE SCHOTTKY 60V 5A SMC D12, D19 Unknown server 2
DNP BME280 SENSOR PRESSURE HUMIDITY TEMP U14 Unknown server 1
DNP BMX160 IMU ACCEL/GYRO/MAG U13 Unknown server 1